(kicad_pcb
	(version 20221018)
	(generator pcbnew)
	(general
    (thickness 1.6)
  )
	(paper "A4")
	(title_block
    (title "NUC Computer Cluster Power Breakout HW")
    (date "2023-10-18")
    (rev "1.4.3")
    (company "Antmicro Ltd.")
		(comment 9 "footprints 117-124 of 234")
	)
	(layers
    (0 "F.Cu" mixed)
    (1 "In1.Cu" power)
    (2 "In2.Cu" mixed)
    (31 "B.Cu" power)
    (32 "B.Adhes" user "B.Adhesive")
    (33 "F.Adhes" user "F.Adhesive")
    (34 "B.Paste" user)
    (35 "F.Paste" user)
    (36 "B.SilkS" user "B.Silkscreen")
    (37 "F.SilkS" user "F.Silkscreen")
    (38 "B.Mask" user)
    (39 "F.Mask" user)
    (40 "Dwgs.User" user "User.Drawings")
    (41 "Cmts.User" user "User.Comments")
    (42 "Eco1.User" user "User.Eco1")
    (43 "Eco2.User" user "User.Eco2")
    (44 "Edge.Cuts" user)
    (45 "Margin" user)
    (46 "B.CrtYd" user "B.Courtyard")
    (47 "F.CrtYd" user "F.Courtyard")
    (48 "B.Fab" user)
    (49 "F.Fab" user)
  )
	(footprint "antmicro-footprints:C_0402_1005Metric" (layer "F.Cu")
    (at 167.45 117.435 90)
    (descr "Capacitor SMD 0402")
    (tags "capacitor SMD 0402")
    (property "Author" "Antmicro")
    (property "Dielectric" "X5R")
    (property "License" "Apache-2.0")
    (property "MPN" "GRM155R61H104KE14D")
    (property "Manufacturer" "Murata")
    (property "Sheetfile" "ftdi-module.kicad_sch")
    (property "Sheetname" "FTDI")
    (property "Val" "100n")
    (property "Voltage" "50V")
    (property "ki_description" "SMD Multilayer Ceramic Capacitor, 0.1 µF, 50 V, 0402 [1005 Metric], ± 10%, X5R, GRM Series")
    (property "ki_keywords" "0402, SMT, CAPACITOR, PASSIVE, CERAMIC, MLCC")
    (attr smd)
    (fp_text reference "C14" (at 0.885 0.45 90) (layer "F.SilkS")
        (effects (font (size 0.7 0.7) (thickness 0.15)) (justify left bottom))
    )
    (fp_text value "C_100n_0402" (at -1.022927 2.155213 90) (layer "F.Fab")
        (effects (font (size 0.7 0.7) (thickness 0.15)) (justify left bottom))
    )
    (fp_text user "${REFERENCE}" (at -0.939 4.599 90) (layer "F.Fab") hide
        (effects (font (size 0.7 0.7) (thickness 0.15)) (justify left bottom))
    )
    (fp_text user "License: Apache-2.0" (at -0.939 5.799 90) (layer "F.Fab") hide
        (effects (font (size 0.7 0.7) (thickness 0.15)) (justify left bottom))
    )
    (fp_text user "Author: Antmicro" (at -0.939 3.399 90) (layer "F.Fab") hide
        (effects (font (size 0.7 0.7) (thickness 0.15)) (justify left bottom))
    )
    (fp_rect (start -0.925 -0.47) (end 0.925 0.47)
      (stroke (width 0.05) (type default)) (fill none) (layer "F.CrtYd"))
    (fp_line (start -0.494 -0.25) (end 0.504 -0.25)
      (stroke (width 0.15) (type solid)) (layer "F.Fab"))
    (fp_line (start -0.494 0.248) (end -0.494 -0.25)
      (stroke (width 0.15) (type solid)) (layer "F.Fab"))
    (fp_line (start 0.504 -0.25) (end 0.504 0.248)
      (stroke (width 0.15) (type solid)) (layer "F.Fab"))
    (fp_line (start 0.504 0.248) (end -0.494 0.248)
      (stroke (width 0.15) (type solid)) (layer "F.Fab"))
    (pad "1" smd roundrect (at -0.48 0 90) (size 0.59 0.64) (layers "F.Cu" "F.Paste" "F.Mask") (roundrect_rratio 0.25)
      (net 6 "/FTDI/FTDI_VPLL") (pintype "passive"))
    (pad "2" smd roundrect (at 0.48 0 90) (size 0.59 0.64) (layers "F.Cu" "F.Paste" "F.Mask") (roundrect_rratio 0.25)
      (net 77 "GNDD") (pintype "passive"))
  )
	(footprint "antmicro-footprints:C_0402_1005Metric" (layer "F.Cu")
    (at 168.9575 120.915 90)
    (descr "Capacitor SMD 0402")
    (tags "capacitor SMD 0402")
    (property "Author" "Antmicro")
    (property "Dielectric" "X5R")
    (property "License" "Apache-2.0")
    (property "MPN" "GRM155R61H104KE14D")
    (property "Manufacturer" "Murata")
    (property "Sheetfile" "ftdi-module.kicad_sch")
    (property "Sheetname" "FTDI")
    (property "Val" "100n")
    (property "Voltage" "50V")
    (property "ki_description" "SMD Multilayer Ceramic Capacitor, 0.1 µF, 50 V, 0402 [1005 Metric], ± 10%, X5R, GRM Series")
    (property "ki_keywords" "0402, SMT, CAPACITOR, PASSIVE, CERAMIC, MLCC")
    (attr smd)
    (fp_text reference "C15" (at 0.965 1.1425 90) (layer "F.SilkS")
        (effects (font (size 0.7 0.7) (thickness 0.15)) (justify left bottom))
    )
    (fp_text value "C_100n_0402" (at -1.022927 2.155213 90) (layer "F.Fab")
        (effects (font (size 0.7 0.7) (thickness 0.15)) (justify left bottom))
    )
    (fp_text user "${REFERENCE}" (at -0.939 4.599 90) (layer "F.Fab") hide
        (effects (font (size 0.7 0.7) (thickness 0.15)) (justify left bottom))
    )
    (fp_text user "Author: Antmicro" (at -0.939 3.399 90) (layer "F.Fab") hide
        (effects (font (size 0.7 0.7) (thickness 0.15)) (justify left bottom))
    )
    (fp_text user "License: Apache-2.0" (at -0.939 5.799 90) (layer "F.Fab") hide
        (effects (font (size 0.7 0.7) (thickness 0.15)) (justify left bottom))
    )
    (fp_rect (start -0.925 -0.47) (end 0.925 0.47)
      (stroke (width 0.05) (type default)) (fill none) (layer "F.CrtYd"))
    (fp_line (start -0.494 -0.25) (end 0.504 -0.25)
      (stroke (width 0.15) (type solid)) (layer "F.Fab"))
    (fp_line (start -0.494 0.248) (end -0.494 -0.25)
      (stroke (width 0.15) (type solid)) (layer "F.Fab"))
    (fp_line (start 0.504 -0.25) (end 0.504 0.248)
      (stroke (width 0.15) (type solid)) (layer "F.Fab"))
    (fp_line (start 0.504 0.248) (end -0.494 0.248)
      (stroke (width 0.15) (type solid)) (layer "F.Fab"))
    (pad "1" smd roundrect (at -0.48 0 90) (size 0.59 0.64) (layers "F.Cu" "F.Paste" "F.Mask") (roundrect_rratio 0.25)
      (net 8 "/FTDI/FTDI_VPHY") (pintype "passive"))
    (pad "2" smd roundrect (at 0.48 0 90) (size 0.59 0.64) (layers "F.Cu" "F.Paste" "F.Mask") (roundrect_rratio 0.25)
      (net 77 "GNDD") (pintype "passive"))
  )
	(footprint "antmicro-footprints:C_0402_1005Metric" (layer "F.Cu")
    (at 170.0575 120.9 90)
    (descr "Capacitor SMD 0402")
    (tags "capacitor SMD 0402")
    (property "Author" "Antmicro")
    (property "Dielectric" "")
    (property "License" "Apache-2.0")
    (property "MPN" "GRM155R61A475MEAAD")
    (property "Manufacturer" "Murata")
    (property "Sheetfile" "ftdi-module.kicad_sch")
    (property "Sheetname" "FTDI")
    (property "Val" "4u7")
    (property "Voltage" "")
    (property "ki_description" "SMD Multilayer Ceramic Capacitor, 4.7 µF, 10 V, 0402 [1005 Metric], ± 20%, X5R, GRM Series")
    (property "ki_keywords" "0402, SMT, CAPACITOR, PASSIVE")
    (attr smd)
    (fp_text reference "C12" (at 0.9 1.0925 90) (layer "F.SilkS")
        (effects (font (size 0.7 0.7) (thickness 0.15)) (justify left bottom))
    )
    (fp_text value "C_4u7_0402" (at -1.022927 2.155213 90) (layer "F.Fab")
        (effects (font (size 0.7 0.7) (thickness 0.15)) (justify left bottom))
    )
    (fp_text user "Author: Antmicro" (at -0.939 3.399 90) (layer "F.Fab") hide
        (effects (font (size 0.7 0.7) (thickness 0.15)) (justify left bottom))
    )
    (fp_text user "License: Apache-2.0" (at -0.939 5.799 90) (layer "F.Fab") hide
        (effects (font (size 0.7 0.7) (thickness 0.15)) (justify left bottom))
    )
    (fp_text user "${REFERENCE}" (at -0.939 4.599 90) (layer "F.Fab") hide
        (effects (font (size 0.7 0.7) (thickness 0.15)) (justify left bottom))
    )
    (fp_rect (start -0.925 -0.47) (end 0.925 0.47)
      (stroke (width 0.05) (type default)) (fill none) (layer "F.CrtYd"))
    (fp_line (start -0.494 -0.25) (end 0.504 -0.25)
      (stroke (width 0.15) (type solid)) (layer "F.Fab"))
    (fp_line (start -0.494 0.248) (end -0.494 -0.25)
      (stroke (width 0.15) (type solid)) (layer "F.Fab"))
    (fp_line (start 0.504 -0.25) (end 0.504 0.248)
      (stroke (width 0.15) (type solid)) (layer "F.Fab"))
    (fp_line (start 0.504 0.248) (end -0.494 0.248)
      (stroke (width 0.15) (type solid)) (layer "F.Fab"))
    (pad "1" smd roundrect (at -0.48 0 90) (size 0.59 0.64) (layers "F.Cu" "F.Paste" "F.Mask") (roundrect_rratio 0.25)
      (net 8 "/FTDI/FTDI_VPHY") (pintype "passive"))
    (pad "2" smd roundrect (at 0.48 0 90) (size 0.59 0.64) (layers "F.Cu" "F.Paste" "F.Mask") (roundrect_rratio 0.25)
      (net 77 "GNDD") (pintype "passive"))
  )
	(footprint "antmicro-footprints:C_0402_1005Metric" (layer "F.Cu")
    (at 162.185 113.9)
    (descr "Capacitor SMD 0402")
    (tags "capacitor SMD 0402")
    (property "Author" "Antmicro")
    (property "Dielectric" "X5R")
    (property "License" "Apache-2.0")
    (property "MPN" "GRM155R61H104KE14D")
    (property "Manufacturer" "Murata")
    (property "Sheetfile" "ftdi-module.kicad_sch")
    (property "Sheetname" "FTDI")
    (property "Val" "100n")
    (property "Voltage" "50V")
    (property "ki_description" "SMD Multilayer Ceramic Capacitor, 0.1 µF, 50 V, 0402 [1005 Metric], ± 10%, X5R, GRM Series")
    (property "ki_keywords" "0402, SMT, CAPACITOR, PASSIVE, CERAMIC, MLCC")
    (attr smd)
    (fp_text reference "C3" (at -1.385 -0.5) (layer "F.SilkS")
        (effects (font (size 0.7 0.7) (thickness 0.15)) (justify left bottom))
    )
    (fp_text value "C_100n_0402" (at -1.022927 2.155213) (layer "F.Fab")
        (effects (font (size 0.7 0.7) (thickness 0.15)) (justify left bottom))
    )
    (fp_text user "License: Apache-2.0" (at -0.939 5.799) (layer "F.Fab") hide
        (effects (font (size 0.7 0.7) (thickness 0.15)) (justify left bottom))
    )
    (fp_text user "${REFERENCE}" (at -0.939 4.599) (layer "F.Fab") hide
        (effects (font (size 0.7 0.7) (thickness 0.15)) (justify left bottom))
    )
    (fp_text user "Author: Antmicro" (at -0.939 3.399) (layer "F.Fab") hide
        (effects (font (size 0.7 0.7) (thickness 0.15)) (justify left bottom))
    )
    (fp_rect (start -0.925 -0.47) (end 0.925 0.47)
      (stroke (width 0.05) (type default)) (fill none) (layer "F.CrtYd"))
    (fp_line (start -0.494 -0.25) (end 0.504 -0.25)
      (stroke (width 0.15) (type solid)) (layer "F.Fab"))
    (fp_line (start -0.494 0.248) (end -0.494 -0.25)
      (stroke (width 0.15) (type solid)) (layer "F.Fab"))
    (fp_line (start 0.504 -0.25) (end 0.504 0.248)
      (stroke (width 0.15) (type solid)) (layer "F.Fab"))
    (fp_line (start 0.504 0.248) (end -0.494 0.248)
      (stroke (width 0.15) (type solid)) (layer "F.Fab"))
    (pad "1" smd roundrect (at -0.48 0) (size 0.59 0.64) (layers "F.Cu" "F.Paste" "F.Mask") (roundrect_rratio 0.25)
      (net 77 "GNDD") (pintype "passive"))
    (pad "2" smd roundrect (at 0.48 0) (size 0.59 0.64) (layers "F.Cu" "F.Paste" "F.Mask") (roundrect_rratio 0.25)
      (net 76 "VCC3V3_USB") (pintype "passive"))
  )
	(footprint "antmicro-footprints:FB_0603_1608Metric" (layer "F.Cu")
    (at 171.9575 121.4)
    (property "Author" "Antmicro")
    (property "Current" "")
    (property "License" "Apache-2.0")
    (property "MPN" "BLM18AG601SN1D")
    (property "Manufacturer" "Murata")
    (property "Sheetfile" "ftdi-module.kicad_sch")
    (property "Sheetname" "FTDI")
    (property "Val" "600Z/0.5A")
    (property "ki_description" "Ferrite Bead, 0603 [1608 Metric], 600 ohm, 500 mA, BLM18A, 0.38 ohm, ± 25%, General use")
    (property "ki_keywords" "0603, SMT, FERRITE BEAD, PASSIVE")
    (attr smd)
    (fp_text reference "FB2" (at 1.1925 0.25) (layer "F.SilkS")
        (effects (font (size 0.7 0.7) (thickness 0.15)) (justify left bottom))
    )
    (fp_text value "FB_600Z_0.5A_Murata-BLM18AG_0603" (at 0 1.5) (layer "F.Fab")
        (effects (font (size 0.7 0.7) (thickness 0.15)) (justify left bottom))
    )
    (fp_text user "Author: Antmicro" (at -1.653 3.162) (layer "F.Fab") hide
        (effects (font (size 0.7 0.7) (thickness 0.15)) (justify left bottom))
    )
    (fp_text user "License: Apache-2.0" (at -1.653 5.9) (layer "F.Fab") hide
        (effects (font (size 0.7 0.7) (thickness 0.15)) (justify left bottom))
    )
    (fp_text user "${REFERENCE}" (at -1.653 4.6) (layer "F.Fab") hide
        (effects (font (size 0.7 0.7) (thickness 0.15)) (justify left bottom))
    )
    (fp_line (start -0.15 -0.4) (end 0.15 -0.4)
      (stroke (width 0.15) (type solid)) (layer "F.SilkS"))
    (fp_line (start -0.15 0.4) (end 0.15 0.4)
      (stroke (width 0.15) (type solid)) (layer "F.SilkS"))
    (fp_rect (start -1.25 -0.65) (end 1.25 0.65)
      (stroke (width 0.05) (type solid)) (fill none) (layer "F.CrtYd"))
    (fp_line (start -0.803 0.406) (end -0.803 -0.408)
      (stroke (width 0.15) (type solid)) (layer "F.Fab"))
    (fp_line (start 0.8 -0.408) (end -0.803 -0.408)
      (stroke (width 0.15) (type solid)) (layer "F.Fab"))
    (fp_line (start 0.8 -0.408) (end 0.8 0.406)
      (stroke (width 0.15) (type solid)) (layer "F.Fab"))
    (fp_line (start 0.8 0.406) (end -0.803 0.406)
      (stroke (width 0.15) (type solid)) (layer "F.Fab"))
    (pad "1" smd roundrect (at -0.7 0) (size 0.8 1) (layers "F.Cu" "F.Paste" "F.Mask") (roundrect_rratio 0.2)
      (net 8 "/FTDI/FTDI_VPHY") (pintype "passive"))
    (pad "2" smd roundrect (at 0.7 0) (size 0.8 1) (layers "F.Cu" "F.Paste" "F.Mask") (roundrect_rratio 0.2)
      (net 76 "VCC3V3_USB") (pintype "passive"))
  )
	(footprint "antmicro-footprints:C_0402_1005Metric" (layer "F.Cu")
    (at 154.6 116.4 -90)
    (descr "Capacitor SMD 0402")
    (tags "capacitor SMD 0402")
    (property "Author" "Antmicro")
    (property "Dielectric" "X5R")
    (property "License" "Apache-2.0")
    (property "MPN" "GRM155R61H104KE14D")
    (property "Manufacturer" "Murata")
    (property "Sheetfile" "ftdi-module.kicad_sch")
    (property "Sheetname" "FTDI")
    (property "Val" "100n")
    (property "Voltage" "50V")
    (property "ki_description" "SMD Multilayer Ceramic Capacitor, 0.1 µF, 50 V, 0402 [1005 Metric], ± 10%, X5R, GRM Series")
    (property "ki_keywords" "0402, SMT, CAPACITOR, PASSIVE, CERAMIC, MLCC")
    (zone_connect 1)
    (attr smd)
    (fp_text reference "C10" (at -2.1 0.6 90) (layer "F.SilkS")
        (effects (font (size 0.7 0.7) (thickness 0.15)) (justify right bottom))
    )
    (fp_text value "C_100n_0402" (at -1.022927 2.155213 90) (layer "F.Fab")
        (effects (font (size 0.7 0.7) (thickness 0.15)) (justify right bottom))
    )
    (fp_text user "License: Apache-2.0" (at -0.939 5.799 90) (layer "F.Fab") hide
        (effects (font (size 0.7 0.7) (thickness 0.15)) (justify right bottom))
    )
    (fp_text user "Author: Antmicro" (at -0.939 3.399 90) (layer "F.Fab") hide
        (effects (font (size 0.7 0.7) (thickness 0.15)) (justify right bottom))
    )
    (fp_text user "${REFERENCE}" (at -0.939 4.599 90) (layer "F.Fab") hide
        (effects (font (size 0.7 0.7) (thickness 0.15)) (justify right bottom))
    )
    (fp_rect (start -0.925 -0.47) (end 0.925 0.47)
      (stroke (width 0.05) (type default)) (fill none) (layer "F.CrtYd"))
    (fp_line (start -0.494 -0.25) (end 0.504 -0.25)
      (stroke (width 0.15) (type solid)) (layer "F.Fab"))
    (fp_line (start -0.494 0.248) (end -0.494 -0.25)
      (stroke (width 0.15) (type solid)) (layer "F.Fab"))
    (fp_line (start 0.504 -0.25) (end 0.504 0.248)
      (stroke (width 0.15) (type solid)) (layer "F.Fab"))
    (fp_line (start 0.504 0.248) (end -0.494 0.248)
      (stroke (width 0.15) (type solid)) (layer "F.Fab"))
    (pad "1" smd roundrect (at -0.48 0 270) (size 0.59 0.64) (layers "F.Cu" "F.Paste" "F.Mask") (roundrect_rratio 0.25)
      (net 77 "GNDD") (pintype "passive"))
    (pad "2" smd roundrect (at 0.48 0 270) (size 0.59 0.64) (layers "F.Cu" "F.Paste" "F.Mask") (roundrect_rratio 0.25)
      (net 7 "1V8_FT") (pintype "passive"))
  )
	(footprint "antmicro-footprints:Resonator_SMD_Geyer_KX-7_3.2x2.5x0.8mm" (layer "F.Cu")
    (at 167.815 124.3)
    (property "Author" "Antmicro")
    (property "License" "Apache-2.0")
    (property "MPN" "KX-7_SMD_CRYSTAL_12,0 MHZ")
    (property "Manufacturer" "Geyer Electronic")
    (property "Sheetfile" "ftdi-module.kicad_sch")
    (property "Sheetname" "FTDI")
    (property "Val" "12 MHz")
    (property "ki_description" "Crystal, 12 MHz, SMT, 3.2mm x 2.5mm, 30 ppm, 12 pF, KX-7")
    (property "ki_keywords" "SMT, CERAMIC, OSCILLATOR")
    (attr smd)
    (fp_text reference "Y1" (at -1.465 2.9) (layer "F.SilkS")
        (effects (font (size 0.7 0.7) (thickness 0.15)) (justify left bottom))
    )
    (fp_text value "Resonator_12MHz_KX_7" (at 0 2.85) (layer "F.Fab")
        (effects (font (size 0.7 0.7) (thickness 0.15)) (justify left bottom))
    )
    (fp_text user "${REFERENCE}" (at -1.75 4.884) (layer "F.Fab") hide
        (effects (font (size 0.7 0.7) (thickness 0.15)) (justify left bottom))
    )
    (fp_text user "Author: Antmicro" (at -1.75 6.084) (layer "F.Fab") hide
        (effects (font (size 0.7 0.7) (thickness 0.15)) (justify left bottom))
    )
    (fp_text user "License: Apache-2.0" (at -1.75 7.283) (layer "F.Fab") hide
        (effects (font (size 0.7 0.7) (thickness 0.15)) (justify left bottom))
    )
    (fp_line (start -1.4 -0.3) (end -1.4 0.28)
      (stroke (width 0.15) (type solid)) (layer "F.SilkS"))
    (fp_line (start 1.399 -0.3) (end 1.399 0.28)
      (stroke (width 0.15) (type solid)) (layer "F.SilkS"))
    (fp_circle (center -1.65 -1.7) (end -1.6 -1.7)
      (stroke (width 0.15) (type solid)) (fill solid) (layer "F.SilkS"))
    (fp_rect (start -1.55 -1.9) (end 1.55 1.9)
      (stroke (width 0.05) (type solid)) (fill none) (layer "F.CrtYd"))
    (fp_line (start -1.25 -1.35) (end -1.25 1.6)
      (stroke (width 0.15) (type solid)) (layer "F.Fab"))
    (fp_line (start -1.25 -1.35) (end -1 -1.601)
      (stroke (width 0.15) (type solid)) (layer "F.Fab"))
    (fp_line (start -1 -1.601) (end 1.249 -1.601)
      (stroke (width 0.15) (type solid)) (layer "F.Fab"))
    (fp_line (start 1.249 -1.601) (end 1.249 1.6)
      (stroke (width 0.15) (type solid)) (layer "F.Fab"))
    (fp_line (start 1.249 1.6) (end -1.25 1.6)
      (stroke (width 0.15) (type solid)) (layer "F.Fab"))
    (pad "1" smd rect (at -0.9 -1.15) (size 1.1 1.3) (layers "F.Cu" "F.Paste" "F.Mask")
      (net 125 "/FTDI/OSCO") (pintype "passive"))
    (pad "2" smd rect (at -0.9 1.15) (size 1.1 1.3) (layers "F.Cu" "F.Paste" "F.Mask")
      (net 77 "GNDD") (pinfunction "SH") (pintype "passive"))
    (pad "3" smd rect (at 0.9 1.15) (size 1.1 1.3) (layers "F.Cu" "F.Paste" "F.Mask")
      (net 5 "/FTDI/OSCI") (pintype "passive"))
    (pad "4" smd rect (at 0.9 -1.15) (size 1.1 1.3) (layers "F.Cu" "F.Paste" "F.Mask")
      (net 77 "GNDD") (pinfunction "SH") (pintype "passive"))
  )
	(footprint "antmicro-footprints:C_0402_1005Metric" (layer "F.Cu")
    (at 156.6 126.8 180)
    (descr "Capacitor SMD 0402")
    (tags "capacitor SMD 0402")
    (property "Author" "Antmicro")
    (property "Dielectric" "")
    (property "License" "Apache-2.0")
    (property "MPN" "GRM155R61A475MEAAD")
    (property "Manufacturer" "Murata")
    (property "Sheetfile" "ftdi-module.kicad_sch")
    (property "Sheetname" "FTDI")
    (property "Val" "4u7")
    (property "Voltage" "")
    (property "ki_description" "SMD Multilayer Ceramic Capacitor, 4.7 µF, 10 V, 0402 [1005 Metric], ± 20%, X5R, GRM Series")
    (property "ki_keywords" "0402, SMT, CAPACITOR, PASSIVE")
    (attr smd)
    (fp_text reference "C13" (at -3.05 -0.4) (layer "F.SilkS")
        (effects (font (size 0.7 0.7) (thickness 0.15)) (justify right bottom))
    )
    (fp_text value "C_4u7_0402" (at -1.022927 2.155213) (layer "F.Fab")
        (effects (font (size 0.7 0.7) (thickness 0.15)) (justify right bottom))
    )
    (fp_text user "Author: Antmicro" (at -0.939 3.399) (layer "F.Fab") hide
        (effects (font (size 0.7 0.7) (thickness 0.15)) (justify right bottom))
    )
    (fp_text user "License: Apache-2.0" (at -0.939 5.799) (layer "F.Fab") hide
        (effects (font (size 0.7 0.7) (thickness 0.15)) (justify right bottom))
    )
    (fp_text user "${REFERENCE}" (at -0.939 4.599) (layer "F.Fab") hide
        (effects (font (size 0.7 0.7) (thickness 0.15)) (justify right bottom))
    )
    (fp_rect (start -0.925 -0.47) (end 0.925 0.47)
      (stroke (width 0.05) (type default)) (fill none) (layer "F.CrtYd"))
    (fp_line (start -0.494 -0.25) (end 0.504 -0.25)
      (stroke (width 0.15) (type solid)) (layer "F.Fab"))
    (fp_line (start -0.494 0.248) (end -0.494 -0.25)
      (stroke (width 0.15) (type solid)) (layer "F.Fab"))
    (fp_line (start 0.504 -0.25) (end 0.504 0.248)
      (stroke (width 0.15) (type solid)) (layer "F.Fab"))
    (fp_line (start 0.504 0.248) (end -0.494 0.248)
      (stroke (width 0.15) (type solid)) (layer "F.Fab"))
    (pad "1" smd roundrect (at -0.48 0 180) (size 0.59 0.64) (layers "F.Cu" "F.Paste" "F.Mask") (roundrect_rratio 0.25)
      (net 77 "GNDD") (pintype "passive"))
    (pad "2" smd roundrect (at 0.48 0 180) (size 0.59 0.64) (layers "F.Cu" "F.Paste" "F.Mask") (roundrect_rratio 0.25)
      (net 7 "1V8_FT") (pintype "passive"))
  )
)
